# S9S_MB_2U (Grand Teton) — schematic netlist excerpt (pin names and nets, part order shuffled) for the footprints in the layout excerpt that follows; sources: Cadence DE-HDL packaged netlist, KiCad conversion of 03242023_DA0F0TMBIJ0_F0T_Motherboard_J_brd_V01_OCP.brd

J21  SCONN288_ADR50017P130CC  SCONN288_ADR50017-P130CC IO  pkg DDR288S_1-1VXB  page 102
  VIN_BULK0  = P12V_S3_AUX_CPU1_NVDIMM
  RFU0  = TP_CHC_CPU1_DIMM1_FRU_0
  VIN_MGMT  = P3V3_AUX
  HSCL  = I3C_SPD_DDRABCD_CPU1_LVC1_SCL_4
  HSDA  = I3C_SPD_DDRABCD_CPU1_LVC1_SDA
  VSS0  = GND
  DQ0_A  = M_C_CPU1_SA_DQ<0>
  VSS1  = GND
  DQ1_A  = M_C_CPU1_SA_DQ<1>
  VSS2  = GND
  DQS0_A_T  = M_C_CPU1_SA_DQS_DP<0>
  DQS0_A_C  = M_C_CPU1_SA_DQS_DN<0>
  VSS3  = GND
  DQ4_A  = M_C_CPU1_SA_DQ<4>
  VSS4  = GND
  DQ5_A  = M_C_CPU1_SA_DQ<5>
  VSS5  = GND
  DQ8_A  = M_C_CPU1_SA_DQ<8>
  VSS6  = GND
  DQ9_A  = M_C_CPU1_SA_DQ<9>
  VSS7  = GND
  DQS1_A_T  = M_C_CPU1_SA_DQS_DP<1>
  DQS1_A_C  = M_C_CPU1_SA_DQS_DN<1>
  VSS8  = GND
  DQ12_A  = M_C_CPU1_SA_DQ<12>
  VSS9  = GND
  DQ13_A  = M_C_CPU1_SA_DQ<13>
  VSS10  = GND
  DQ16_A  = M_C_CPU1_SA_DQ<16>
  VSS11  = GND
  DQ17_A  = M_C_CPU1_SA_DQ<17>
  VSS12  = GND
  DQS2_A_T  = M_C_CPU1_SA_DQS_DP<2>
  DQS2_A_C  = M_C_CPU1_SA_DQS_DN<2>
  VSS13  = GND
  DQ20_A  = M_C_CPU1_SA_DQ<20>
  VSS14  = GND
  DQ21_A  = M_C_CPU1_SA_DQ<21>
  VSS15  = GND
  DQ24_A  = M_C_CPU1_SA_DQ<24>
  VSS16  = GND
  DQ25_A  = M_C_CPU1_SA_DQ<25>
  VSS17  = GND
  DQS3_A_T  = M_C_CPU1_SA_DQS_DP<3>
  DQS3_A_C  = M_C_CPU1_SA_DQS_DN<3>
  VSS18  = GND
  DQ28_A  = M_C_CPU1_SA_DQ<28>
  VSS19  = GND
  DQ29_A  = M_C_CPU1_SA_DQ<29>
  VSS20  = GND
  CB0_A  = M_C_CPU1_SA_CB<0>
  VSS21  = GND
  CB1_A  = M_C_CPU1_SA_CB<1>
  VSS22  = GND
  DQS4_A_T  = M_C_CPU1_SA_DQS_DP<4>
  DQS4_A_C  = M_C_CPU1_SA_DQS_DN<4>
  VSS23  = GND
  CB4_A  = M_C_CPU1_SA_CB<4>
  VSS24  = GND
  CB5_A  = M_C_CPU1_SA_CB<5>
  VSS25  = GND
  ALERT_N  = M_C_CPU1_ALERT_N
  VSS26  = GND
  CS0_A_N  = M_C_CPU1_SA_CS_N<0>
  VSS27  = GND
  CA0_A  = M_C_CPU1_SA_CA<0>
  VSS28  = GND
  CA2_A  = M_C_CPU1_SA_CA<2>
  VSS29  = GND
  CA4_A  = M_C_CPU1_SA_CA<4>
  VSS30  = GND
  CA6_A  = M_C_CPU1_SA_CA<6>
  VSS31  = GND
  PAR_A  = M_C_CPU1_SA_PAR
  VSS32  = GND
  CA0_B  = M_C_CPU1_SB_CA<0>
  VSS33  = GND
  CA2_B  = M_C_CPU1_SB_CA<2>
  VSS34  = GND
  CA4_B  = M_C_CPU1_SB_CA<4>
  VSS35  = GND
  CA6_B  = M_C_CPU1_SB_CA<6>
  VSS36  = GND
  CS0_B_N  = M_C_CPU1_SB_CS_N<0>
  VSS37  = GND
  \lbd||rsp_a_n\  = M_C_CPU1_SA_RSP<0>
  \lbs||rsp_b_n\  = M_C_CPU1_SB_RSP<0>
  VSS38  = GND
  CB4_B  = M_C_CPU1_SB_CB<4>
  VSS39  = GND
  CB5_B  = M_C_CPU1_SB_CB<5>
  VSS40  = GND
  \dqs9_b_t||tdqs9_b_t||dbi4_b_n\  = M_C_CPU1_SB_DQS_DP<9>
  \dqs9_b_c||tdqs9_b_c\  = M_C_CPU1_SB_DQS_DN<9>
  VSS41  = GND
  CB0_B  = M_C_CPU1_SB_CB<0>
  VSS42  = GND
  CB1_B  = M_C_CPU1_SB_CB<1>
  VSS43  = GND
  DQ0_B  = M_C_CPU1_SB_DQ<0>
  VSS44  = GND
  DQ1_B  = M_C_CPU1_SB_DQ<1>
  VSS45  = GND
  DQS0_B_T  = M_C_CPU1_SB_DQS_DP<0>
  DQS0_B_C  = M_C_CPU1_SB_DQS_DN<0>
  VSS46  = GND
  DQ4_B  = M_C_CPU1_SB_DQ<4>
  VSS47  = GND
  DQ5_B  = M_C_CPU1_SB_DQ<5>
  VSS48  = GND
  DQ8_B  = M_C_CPU1_SB_DQ<8>
  VSS49  = GND
  DQ9_B  = M_C_CPU1_SB_DQ<9>
  VSS50  = GND
  DQS1_B_T  = M_C_CPU1_SB_DQS_DP<1>
  DQS1_B_C  = M_C_CPU1_SB_DQS_DN<1>
  VSS51  = GND
  DQ12_B  = M_C_CPU1_SB_DQ<12>
  VSS52  = GND
  DQ13_B  = M_C_CPU1_SB_DQ<13>
  VSS53  = GND
  DQ16_B  = M_C_CPU1_SB_DQ<16>
  VSS54  = GND
  DQ17_B  = M_C_CPU1_SB_DQ<17>
  VSS55  = GND
  DQS2_B_T  = M_C_CPU1_SB_DQS_DP<2>
  DQS2_B_C  = M_C_CPU1_SB_DQS_DN<2>
  VSS56  = GND
  DQ20_B  = M_C_CPU1_SB_DQ<20>
  VSS57  = GND
  DQ21_B  = M_C_CPU1_SB_DQ<21>
  VSS58  = GND
  DQ24_B  = M_C_CPU1_SB_DQ<24>
  VSS59  = GND
  DQ25_B  = M_C_CPU1_SB_DQ<25>
  VSS60  = GND
  DQS3_B_T  = M_C_CPU1_SB_DQS_DP<3>
  DQS3_B_C  = M_C_CPU1_SB_DQS_DN<3>
  VSS61  = GND
  DQ28_B  = M_C_CPU1_SB_DQ<28>
  VSS62  = GND
  DQ29_B  = M_C_CPU1_SB_DQ<29>
  VSS63  = GND
  RFU1  = TP_CHC_CPU1_DIMM1_FRU_1
  VIN_BULK1  = P12V_S3_AUX_CPU1_NVDIMM
  VIN_BULK2  = P12V_S3_AUX_CPU1_NVDIMM
  \pwr_good||fail_n\  = PWRGD_CHC_CPU1_DIMM1
  HSA  = PD_CHC_CPU1_DIMM1_SAA
  RFU2  = TP_CHC_CPU1_DIMM1_FRU_2
  RFU3  = TP_CHC_CPU1_DIMM1_FRU_3
  VSS64  = GND
  DQ2_A  = M_C_CPU1_SA_DQ<2>
  VSS65  = GND
  DQ3_A  = M_C_CPU1_SA_DQ<3>
  VSS66  = GND
  \dqs5_a_c||tdqs5_a_c||dqs5_a_t||tdqs5_a_t\  = M_C_CPU1_SA_DQS_DN<5>
  \dqs5_a_t||tdqs5_a_t\  = M_C_CPU1_SA_DQS_DP<5>
  VSS67  = GND
  DQ6_A  = M_C_CPU1_SA_DQ<6>
  VSS68  = GND
  DQ7_A  = M_C_CPU1_SA_DQ<7>
  VSS69  = GND
  DQ10_A  = M_C_CPU1_SA_DQ<10>
  VSS70  = GND
  DQ11_A  = M_C_CPU1_SA_DQ<11>
  VSS71  = GND
  \dqs6_a_c||tdqs6_a_c||dqs6_a_t||tdqs6_a_t\  = M_C_CPU1_SA_DQS_DN<6>
  \dqs6_a_t||tdqs6_a_t\  = M_C_CPU1_SA_DQS_DP<6>
  VSS72  = GND
  DQ14_A  = M_C_CPU1_SA_DQ<14>
  VSS73  = GND
  DQ15_A  = M_C_CPU1_SA_DQ<15>
  VSS74  = GND
  DQ18_A  = M_C_CPU1_SA_DQ<18>
  VSS75  = GND
  DQ19_A  = M_C_CPU1_SA_DQ<19>
  VSS76  = GND
  \dqs7_a_c||tdqs7_a_c\  = M_C_CPU1_SA_DQS_DN<7>
  \dqs7_a_t||tdqs7_a_t\  = M_C_CPU1_SA_DQS_DP<7>
  VSS77  = GND
  DQ22_A  = M_C_CPU1_SA_DQ<22>
  VSS78  = GND
  DQ23_A  = M_C_CPU1_SA_DQ<23>
  VSS79  = GND
  DQ26_A  = M_C_CPU1_SA_DQ<26>
  VSS80  = GND
  DQ27_A  = M_C_CPU1_SA_DQ<27>
  VSS81  = GND
  \dqs8_a_c||tdqs8_a_c\  = M_C_CPU1_SA_DQS_DN<8>
  \dqs8_a_t||tdqs8_a_t\  = M_C_CPU1_SA_DQS_DP<8>
  VSS82  = GND
  DQ30_A  = M_C_CPU1_SA_DQ<30>
  VSS83  = GND
  DQ31_A  = M_C_CPU1_SA_DQ<31>
  VSS84  = GND
  CB2_A  = M_C_CPU1_SA_CB<2>
  VSS85  = GND
  CB3_A  = M_C_CPU1_SA_CB<3>
  VSS86  = GND
  \dqs9_a_c||tdqs9_a_c\  = M_C_CPU1_SA_DQS_DN<9>
  \dqs9_a_t||tdqs9_a_t\  = M_C_CPU1_SA_DQS_DP<9>
  VSS87  = GND
  CB6_A  = M_C_CPU1_SA_CB<6>
  VSS88  = GND
  CB7_A  = M_C_CPU1_SA_CB<7>
  VSS89  = GND
  RESET_N  = RST_M_CD_CPU1_FPGA_N
  VSS90  = GND
  CS1_A_N  = M_C_CPU1_SA_CS_N<1>
  VSS91  = GND
  CA1_A  = M_C_CPU1_SA_CA<1>
  VSS92  = GND
  CA3_A  = M_C_CPU1_SA_CA<3>
  VSS93  = GND
  CA5_A  = M_C_CPU1_SA_CA<5>
  VSS94  = GND
  CK_T  = M_C_CPU1_CLK_DP<0>
  CK_C  = M_C_CPU1_CLK_DN<0>
  VSS95  = GND
  RFU4  = TP_CHC_CPU1_DIMM1_FRU_4
  CA1_B  = M_C_CPU1_SB_CA<1>
  VSS96  = GND
  CA3_B  = M_C_CPU1_SB_CA<3>
  VSS97  = GND
  CA5_B  = M_C_CPU1_SB_CA<5>
  VSS98  = GND
  PAR_B  = M_C_CPU1_SB_PAR
  VSS99  = GND
  CS1_B_N  = M_C_CPU1_SB_CS_N<1>
  VSS100  = GND
  RFU5  = TP_CHC_CPU1_DIMM1_FRU_5
  RFU6  = TP_CHC_CPU1_DIMM1_FRU_6
  VSS101  = GND
  CB6_B  = M_C_CPU1_SB_CB<6>
  VSS102  = GND
  CB7_B  = M_C_CPU1_SB_CB<7>
  VSS103  = GND
  DQS4_B_C  = M_C_CPU1_SB_DQS_DN<4>
  DQS4_B_T  = M_C_CPU1_SB_DQS_DP<4>
  VSS104  = GND
  CB2_B  = M_C_CPU1_SB_CB<2>
  VSS105  = GND
  CB3_B  = M_C_CPU1_SB_CB<3>
  VSS106  = GND
  DQ2_B  = M_C_CPU1_SB_DQ<2>
  VSS107  = GND
  DQ3_B  = M_C_CPU1_SB_DQ<3>
  VSS108  = GND
  \dqs5_b_c||tdqs5_b_c\  = M_C_CPU1_SB_DQS_DN<5>
  \dqs5_b_t||tdqs5_b_t\  = M_C_CPU1_SB_DQS_DP<5>
  VSS109  = GND
  DQ6_B  = M_C_CPU1_SB_DQ<6>
  VSS110  = GND
  DQ7_B  = M_C_CPU1_SB_DQ<7>
  VSS111  = GND
  DQ10_B  = M_C_CPU1_SB_DQ<10>
  VSS112  = GND
  DQ11_B  = M_C_CPU1_SB_DQ<11>
  VSS113  = GND
  \dqs6_b_c||tdqs6_b_c\  = M_C_CPU1_SB_DQS_DN<6>
  \dqs6_b_t||tdqs6_b_t\  = M_C_CPU1_SB_DQS_DP<6>
  VSS114  = GND
  DQ14_B  = M_C_CPU1_SB_DQ<14>
  VSS115  = GND
  DQ15_B  = M_C_CPU1_SB_DQ<15>
  VSS116  = GND
  DQ18_B  = M_C_CPU1_SB_DQ<18>
  VSS117  = GND
  DQ19_B  = M_C_CPU1_SB_DQ<19>
  VSS118  = GND
  \dqs7_b_c||tdqs7_b_c\  = M_C_CPU1_SB_DQS_DN<7>
  \dqs7_b_t||tdqs7_b_t\  = M_C_CPU1_SB_DQS_DP<7>
  VSS119  = GND
  DQ22_B  = M_C_CPU1_SB_DQ<22>
  VSS120  = GND
  DQ23_B  = M_C_CPU1_SB_DQ<23>
  VSS121  = GND
  DQ26_B  = M_C_CPU1_SB_DQ<26>
  VSS122  = GND
  DQ27_B  = M_C_CPU1_SB_DQ<27>
  VSS123  = GND
  \dqs8_b_c||tdqs8_b_c\  = M_C_CPU1_SB_DQS_DN<8>
  \dqs8_b_t||tdqs8_b_t\  = M_C_CPU1_SB_DQS_DP<8>
  VSS124  = GND
  DQ30_B  = M_C_CPU1_SB_DQ<30>
  VSS125  = GND
  DQ31_B  = M_C_CPU1_SB_DQ<31>
  VSS126  = GND
  G1  = GND
  G2  = GND
  G3  = GND

(kicad_pcb
	(version 20260206)
	(generator "pcbnew")
	(generator_version "10.0")
	(general
		(thickness 1.6)
		(legacy_teardrops no)
	)
	(paper "A4")
	(title_block
		(title "03242023_DA0F0TMBIJ0_F0T_Motherboard_J_brd_V01_OCP.brd")
		(comment 1 "Grand Teton / footprint 663 of 6105 (J21), pads 275-291 of 291")
	)
	(layers
		(0 "F.Cu" signal "TOP")
		(4 "In1.Cu" signal "GND")
		(6 "In2.Cu" signal "IN1")
		(8 "In3.Cu" signal "GND1")
		(10 "In4.Cu" signal "IN2")
		(12 "In5.Cu" signal "GND2")
		(14 "In6.Cu" signal "IN3")
		(16 "In7.Cu" signal "GND3")
		(18 "In8.Cu" signal "VCC")
		(20 "In9.Cu" signal "VCC1")
		(22 "In10.Cu" signal "GND4")
		(24 "In11.Cu" signal "IN4")
		(26 "In12.Cu" signal "GND5")
		(28 "In13.Cu" signal "IN5")
		(30 "In14.Cu" signal "GND6")
		(32 "In15.Cu" signal "IN6")
		(34 "In16.Cu" signal "GND7")
		(2 "B.Cu" signal "BOTTOM")
		(9 "F.Adhes" user "F.Adhesive")
		(11 "B.Adhes" user "B.Adhesive")
		(13 "F.Paste" user "Package Geometry/Pastemask Top")
		(15 "B.Paste" user "Package Geometry/Pastemask Bottom")
		(5 "F.SilkS" user "Ref Des/Silkscreen Top")
		(7 "B.SilkS" user "Ref Des/Silkscreen Bottom")
		(1 "F.Mask" user "Board Geometry/Soldermask Top")
		(3 "B.Mask" user "Board Geometry/Soldermask Bottom")
		(17 "Dwgs.User" user "User.Drawings")
		(19 "Cmts.User" user "User.Comments")
		(21 "Eco1.User" user "User.Eco1")
		(23 "Eco2.User" user "User.Eco2")
		(25 "Edge.Cuts" user "Board Geometry/Outline")
		(27 "Margin" user)
		(31 "F.CrtYd" user "Package Geometry/Place Bound Top")
		(29 "B.CrtYd" user "Package Geometry/Place Bound Bottom")
		(35 "F.Fab" user "Ref Des/Assembly Top")
		(33 "B.Fab" user "Ref Des/Assembly Bottom")
	)
	(footprint ""
		(layer "F.Cu")
		(at 25.27808 -258.091686)
		(property "Reference" "J21"
			(at -0.325882 -81.821274 0)
			(unlocked yes)
			(layer "F.SilkS")
			(effects
				(font
					(size 0.7874 0.5842)
					(thickness 0.1524)
				)
				(justify left)
			)
		)
		(property "Value" ""
			(at 0 0 0)
			(layer "F.Fab")
			(effects
				(font
					(size 1.27 1.27)
				)
			)
		)
		(duplicate_pad_numbers_are_jumpers no)
		(pad "275" smd rect
			(at 2.050034 52.274978 270)
			(size 0.519938 1.4986)
			(layers "F.Cu" "F.Mask" "F.Paste")
			(net "GND")
		)
		(pad "276" smd rect
			(at 2.050034 53.125116 270)
			(size 0.519938 1.4986)
			(layers "F.Cu" "F.Mask" "F.Paste")
			(net "M_C_CPU1_SB_DQ<23>")
		)
		(pad "277" smd rect
			(at 2.050034 53.975 270)
			(size 0.519938 1.4986)
			(layers "F.Cu" "F.Mask" "F.Paste")
			(net "GND")
		)
		(pad "278" smd rect
			(at 2.050034 54.824884 270)
			(size 0.519938 1.4986)
			(layers "F.Cu" "F.Mask" "F.Paste")
			(net "M_C_CPU1_SB_DQ<26>")
		)
		(pad "279" smd rect
			(at 2.050034 55.675022 270)
			(size 0.519938 1.4986)
			(layers "F.Cu" "F.Mask" "F.Paste")
			(net "GND")
		)
		(pad "280" smd rect
			(at 2.050034 56.524906 270)
			(size 0.519938 1.4986)
			(layers "F.Cu" "F.Mask" "F.Paste")
			(net "M_C_CPU1_SB_DQ<27>")
		)
		(pad "281" smd rect
			(at 2.050034 57.375044 270)
			(size 0.519938 1.4986)
			(layers "F.Cu" "F.Mask" "F.Paste")
			(net "GND")
		)
		(pad "282" smd rect
			(at 2.050034 58.224928 270)
			(size 0.519938 1.4986)
			(layers "F.Cu" "F.Mask" "F.Paste")
			(net "M_C_CPU1_SB_DQS_DN<8>")
		)
		(pad "283" smd rect
			(at 2.050034 59.075066 270)
			(size 0.519938 1.4986)
			(layers "F.Cu" "F.Mask" "F.Paste")
			(net "M_C_CPU1_SB_DQS_DP<8>")
		)
		(pad "284" smd rect
			(at 2.050034 59.92495 270)
			(size 0.519938 1.4986)
			(layers "F.Cu" "F.Mask" "F.Paste")
			(net "GND")
		)
		(pad "285" smd rect
			(at 2.050034 60.775088 270)
			(size 0.519938 1.4986)
			(layers "F.Cu" "F.Mask" "F.Paste")
			(net "M_C_CPU1_SB_DQ<30>")
		)
		(pad "286" smd rect
			(at 2.050034 61.624972 270)
			(size 0.519938 1.4986)
			(layers "F.Cu" "F.Mask" "F.Paste")
			(net "GND")
		)
		(pad "287" smd rect
			(at 2.050034 62.47511 270)
			(size 0.519938 1.4986)
			(layers "F.Cu" "F.Mask" "F.Paste")
			(net "M_C_CPU1_SB_DQ<31>")
		)
		(pad "288" smd rect
			(at 2.050034 63.324994 270)
			(size 0.519938 1.4986)
			(layers "F.Cu" "F.Mask" "F.Paste")
			(net "GND")
		)
		(pad "G1" thru_hole oval
			(at 0 -68.97497)
			(size 2.8194 1.5748)
			(drill oval 2.4384 1.1938)
			(layers "*.Cu" "*.Mask")
			(remove_unused_layers no)
			(net "GND")
			(clearance 0.127)
			(thermal_gap 0.127)
		)
		(pad "G2" thru_hole oval
			(at 0 3.875024)
			(size 2.8194 1.5748)
			(drill oval 2.4384 1.1938)
			(layers "*.Cu" "*.Mask")
			(remove_unused_layers no)
			(net "GND")
			(clearance 0.127)
			(thermal_gap 0.127)
		)
		(pad "G3" thru_hole oval
			(at 0 68.97497)
			(size 2.8194 1.5748)
			(drill oval 2.4384 1.1938)
			(layers "*.Cu" "*.Mask")
			(remove_unused_layers no)
			(net "GND")
			(clearance 0.127)
			(thermal_gap 0.127)
		)
	)
)
